# SCM (Grand Teton) — schematic netlist excerpt (pin names and nets, part order shuffled) for the footprints in the layout excerpt that follows; sources: Cadence DE-HDL packaged netlist, KiCad conversion of 12092022_DA0F0TMDCD0_F0T_Management_Board_D_brd_V3_OCP.brd

PR274  Q_RES  0 5% CHIP  pkg 0402LF  page 55 : A = P3V3_AUX ; B = PVCC1_AUX
R514  Q_RES  33.2 1% CHIP  pkg 0402LF  page 32 : A = JTAG_SCM_PLD_TCK ; B = JTAG_SCM_CONN_TCK

(kicad_pcb
	(version 20260206)
	(generator "pcbnew")
	(generator_version "10.0")
	(general
		(thickness 1.6)
		(legacy_teardrops no)
	)
	(paper "A4")
	(title_block
		(title "12092022_DA0F0TMDCD0_F0T_Management_Board_D_brd_V3_OCP.brd")
		(comment 1 "Grand Teton / footprints 661-662 of 1440")
	)
	(layers
		(0 "F.Cu" signal "TOP")
		(4 "In1.Cu" signal "GND")
		(6 "In2.Cu" signal "IN1")
		(8 "In3.Cu" signal "GND1")
		(10 "In4.Cu" signal "IN2")
		(12 "In5.Cu" signal "VCC")
		(14 "In6.Cu" signal "VCC1")
		(16 "In7.Cu" signal "IN3")
		(18 "In8.Cu" signal "GND2")
		(20 "In9.Cu" signal "IN4")
		(22 "In10.Cu" signal "GND3")
		(2 "B.Cu" signal "BOTTOM")
		(9 "F.Adhes" user "F.Adhesive")
		(11 "B.Adhes" user "B.Adhesive")
		(13 "F.Paste" user "Package Geometry/Pastemask Top")
		(15 "B.Paste" user "Package Geometry/Pastemask Bottom")
		(5 "F.SilkS" user "Ref Des/Silkscreen Top")
		(7 "B.SilkS" user "Ref Des/Silkscreen Bottom")
		(1 "F.Mask" user "Board Geometry/Soldermask Top")
		(3 "B.Mask" user "Board Geometry/Soldermask Bottom")
		(17 "Dwgs.User" user "User.Drawings")
		(19 "Cmts.User" user "User.Comments")
		(21 "Eco1.User" user "User.Eco1")
		(23 "Eco2.User" user "User.Eco2")
		(25 "Edge.Cuts" user "Board Geometry/Outline")
		(27 "Margin" user)
		(31 "F.CrtYd" user "Package Geometry/Place Bound Top")
		(29 "B.CrtYd" user "Package Geometry/Place Bound Bottom")
		(35 "F.Fab" user "Ref Des/Assembly Top")
		(33 "B.Fab" user "Ref Des/Assembly Bottom")
	)
	(footprint ""
		(layer "F.Cu")
		(at 83.77555 -70.458838 -90)
		(property "Reference" "PR274"
			(at 0 0 270)
			(layer "F.SilkS")
			(hide yes)
			(effects
				(font
					(size 1.27 1.27)
				)
			)
		)
		(property "Value" ""
			(at 0 0 270)
			(layer "F.Fab")
			(effects
				(font
					(size 1.27 1.27)
				)
			)
		)
		(duplicate_pad_numbers_are_jumpers no)
		(fp_line
			(start -0.7874 0.4064)
			(end -0.7874 -0.4064)
			(stroke
				(width 0.1524)
				(type default)
			)
			(layer "F.SilkS")
		)
		(fp_line
			(start 0.7874 0.4064)
			(end -0.7874 0.4064)
			(stroke
				(width 0.1524)
				(type default)
			)
			(layer "F.SilkS")
		)
		(fp_line
			(start -0.7874 -0.4064)
			(end 0.7874 -0.4064)
			(stroke
				(width 0.1524)
				(type default)
			)
			(layer "F.SilkS")
		)
		(fp_line
			(start 0.7874 -0.4064)
			(end 0.7874 0.4064)
			(stroke
				(width 0.1524)
				(type default)
			)
			(layer "F.SilkS")
		)
		(fp_line
			(start -0.67945 0.3048)
			(end -0.67945 -0.305054)
			(stroke
				(width 0.1)
				(type default)
			)
			(layer "F.Fab")
		)
		(fp_line
			(start -0.12065 0.3048)
			(end -0.67945 0.3048)
			(stroke
				(width 0.1)
				(type default)
			)
			(layer "F.Fab")
		)
		(fp_line
			(start 0.120396 0.3048)
			(end 0.120396 0.2794)
			(stroke
				(width 0.1)
				(type default)
			)
			(layer "F.Fab")
		)
		(fp_line
			(start 0.67945 0.3048)
			(end 0.120396 0.3048)
			(stroke
				(width 0.1)
				(type default)
			)
			(layer "F.Fab")
		)
		(fp_line
			(start -0.12065 0.2794)
			(end -0.12065 0.3048)
			(stroke
				(width 0.1)
				(type default)
			)
			(layer "F.Fab")
		)
		(fp_line
			(start 0.120396 0.2794)
			(end -0.12065 0.2794)
			(stroke
				(width 0.1)
				(type default)
			)
			(layer "F.Fab")
		)
		(fp_line
			(start -0.12065 -0.2794)
			(end 0.12065 -0.2794)
			(stroke
				(width 0.1)
				(type default)
			)
			(layer "F.Fab")
		)
		(fp_line
			(start 0.12065 -0.2794)
			(end 0.12065 -0.3048)
			(stroke
				(width 0.1)
				(type default)
			)
			(layer "F.Fab")
		)
		(fp_line
			(start 0.12065 -0.3048)
			(end 0.67945 -0.3048)
			(stroke
				(width 0.1)
				(type default)
			)
			(layer "F.Fab")
		)
		(fp_line
			(start 0.67945 -0.3048)
			(end 0.67945 0.3048)
			(stroke
				(width 0.1)
				(type default)
			)
			(layer "F.Fab")
		)
		(fp_line
			(start -0.67945 -0.305054)
			(end -0.12065 -0.305054)
			(stroke
				(width 0.1)
				(type default)
			)
			(layer "F.Fab")
		)
		(fp_line
			(start -0.12065 -0.305054)
			(end -0.12065 -0.2794)
			(stroke
				(width 0.1)
				(type default)
			)
			(layer "F.Fab")
		)
		(pad "1" smd circle
			(at -0.40005 0 270)
			(size 0 0)
			(layers "F.Cu" "F.Mask" "F.Paste")
			(net "P3V3_AUX")
		)
		(pad "2" smd circle
			(at 0.40005 0 270)
			(size 0 0)
			(layers "F.Cu" "F.Mask" "F.Paste")
			(net "PVCC1_AUX")
		)
	)
	(footprint ""
		(layer "F.Cu")
		(at 10.287 -91.059 -90)
		(property "Reference" "R514"
			(at 0 0 270)
			(layer "F.SilkS")
			(hide yes)
			(effects
				(font
					(size 1.27 1.27)
				)
			)
		)
		(property "Value" ""
			(at 0 0 270)
			(layer "F.Fab")
			(effects
				(font
					(size 1.27 1.27)
				)
			)
		)
		(duplicate_pad_numbers_are_jumpers no)
		(fp_line
			(start -0.7874 0.4064)
			(end -0.7874 -0.4064)
			(stroke
				(width 0.1524)
				(type default)
			)
			(layer "F.SilkS")
		)
		(fp_line
			(start 0.7874 0.4064)
			(end -0.7874 0.4064)
			(stroke
				(width 0.1524)
				(type default)
			)
			(layer "F.SilkS")
		)
		(fp_line
			(start -0.7874 -0.4064)
			(end 0.7874 -0.4064)
			(stroke
				(width 0.1524)
				(type default)
			)
			(layer "F.SilkS")
		)
		(fp_line
			(start 0.7874 -0.4064)
			(end 0.7874 0.4064)
			(stroke
				(width 0.1524)
				(type default)
			)
			(layer "F.SilkS")
		)
		(fp_line
			(start -0.67945 0.3048)
			(end -0.67945 -0.305054)
			(stroke
				(width 0.1)
				(type default)
			)
			(layer "F.Fab")
		)
		(fp_line
			(start -0.12065 0.3048)
			(end -0.67945 0.3048)
			(stroke
				(width 0.1)
				(type default)
			)
			(layer "F.Fab")
		)
		(fp_line
			(start 0.120396 0.3048)
			(end 0.120396 0.2794)
			(stroke
				(width 0.1)
				(type default)
			)
			(layer "F.Fab")
		)
		(fp_line
			(start 0.67945 0.3048)
			(end 0.120396 0.3048)
			(stroke
				(width 0.1)
				(type default)
			)
			(layer "F.Fab")
		)
		(fp_line
			(start -0.12065 0.2794)
			(end -0.12065 0.3048)
			(stroke
				(width 0.1)
				(type default)
			)
			(layer "F.Fab")
		)
		(fp_line
			(start 0.120396 0.2794)
			(end -0.12065 0.2794)
			(stroke
				(width 0.1)
				(type default)
			)
			(layer "F.Fab")
		)
		(fp_line
			(start -0.12065 -0.2794)
			(end 0.12065 -0.2794)
			(stroke
				(width 0.1)
				(type default)
			)
			(layer "F.Fab")
		)
		(fp_line
			(start 0.12065 -0.2794)
			(end 0.12065 -0.3048)
			(stroke
				(width 0.1)
				(type default)
			)
			(layer "F.Fab")
		)
		(fp_line
			(start 0.12065 -0.3048)
			(end 0.67945 -0.3048)
			(stroke
				(width 0.1)
				(type default)
			)
			(layer "F.Fab")
		)
		(fp_line
			(start 0.67945 -0.3048)
			(end 0.67945 0.3048)
			(stroke
				(width 0.1)
				(type default)
			)
			(layer "F.Fab")
		)
		(fp_line
			(start -0.67945 -0.305054)
			(end -0.12065 -0.305054)
			(stroke
				(width 0.1)
				(type default)
			)
			(layer "F.Fab")
		)
		(fp_line
			(start -0.12065 -0.305054)
			(end -0.12065 -0.2794)
			(stroke
				(width 0.1)
				(type default)
			)
			(layer "F.Fab")
		)
		(pad "1" smd circle
			(at -0.40005 0 270)
			(size 0 0)
			(layers "F.Cu" "F.Mask" "F.Paste")
			(net "JTAG_SCM_PLD_TCK")
		)
		(pad "2" smd circle
			(at 0.40005 0 270)
			(size 0 0)
			(layers "F.Cu" "F.Mask" "F.Paste")
			(net "JTAG_SCM_CONN_TCK")
		)
	)
)
